(kicad_pcb
	(version 20260206)
	(generator "pcbnew")
	(generator_version "10.0")
	(general
		(thickness 1.6)
		(legacy_teardrops no)
	)
	(paper "A4")
	(title_block
		(title "Wiwynn_Tioga_Pass_MB.brd")
		(comment 1 "Tioga Pass / footprints 2839-2846 of 4770")
	)
	(layers
		(0 "F.Cu" signal "TOP")
		(4 "In1.Cu" signal "L2GND")
		(6 "In2.Cu" signal "L3")
		(8 "In3.Cu" signal "L4GND")
		(10 "In4.Cu" signal "L5")
		(12 "In5.Cu" signal "L6GND")
		(14 "In6.Cu" signal "L7VCC")
		(16 "In7.Cu" signal "L8VCC")
		(18 "In8.Cu" signal "L9GND")
		(20 "In9.Cu" signal "L10")
		(22 "In10.Cu" signal "L11GND")
		(24 "In11.Cu" signal "L12")
		(26 "In12.Cu" signal "L13GND")
		(2 "B.Cu" signal "BOTTOM")
		(9 "F.Adhes" user "F.Adhesive")
		(11 "B.Adhes" user "B.Adhesive")
		(13 "F.Paste" user "Package Geometry/Pastemask Top")
		(15 "B.Paste" user "Package Geometry/Pastemask Bottom")
		(5 "F.SilkS" user "Ref Des/Silkscreen Top")
		(7 "B.SilkS" user "Ref Des/Silkscreen Bottom")
		(1 "F.Mask" user "Board Geometry/Soldermask Top")
		(3 "B.Mask" user "Board Geometry/Soldermask Bottom")
		(17 "Dwgs.User" user "User.Drawings")
		(19 "Cmts.User" user "User.Comments")
		(21 "Eco1.User" user "User.Eco1")
		(23 "Eco2.User" user "User.Eco2")
		(25 "Edge.Cuts" user "Board Geometry/Outline")
		(27 "Margin" user)
		(31 "F.CrtYd" user "Package Geometry/Place Bound Top")
		(29 "B.CrtYd" user "Package Geometry/Place Bound Bottom")
		(35 "F.Fab" user "Ref Des/Assembly Top")
		(33 "B.Fab" user "Ref Des/Assembly Bottom")
	)
	(footprint ""
		(layer "B.Cu")
		(at 411.861 -145.415 -90)
		(property "Reference" "C2L27"
			(at 0 0 90)
			(layer "B.SilkS")
			(hide yes)
			(effects
				(font
					(size 1.27 1.27)
				)
				(justify mirror)
			)
		)
		(property "Value" ""
			(at 0 0 90)
			(layer "B.Fab")
			(effects
				(font
					(size 1.27 1.27)
				)
				(justify mirror)
			)
		)
		(duplicate_pad_numbers_are_jumpers no)
		(fp_poly
			(pts
				(xy -0.3048 -0.1016) (xy -0.3048 0.9906) (xy 0.3048 0.9906) (xy 0.3048 -0.1016)
			)
			(stroke
				(width 0)
				(type default)
			)
			(fill no)
			(layer "B.CrtYd")
		)
		(fp_line
			(start -0.3048 0.9906)
			(end -0.3048 -0.1016)
			(stroke
				(width 0.1)
				(type default)
			)
			(layer "B.Fab")
		)
		(fp_line
			(start 0.3048 0.9906)
			(end -0.3048 0.9906)
			(stroke
				(width 0.1)
				(type default)
			)
			(layer "B.Fab")
		)
		(fp_line
			(start -0.3048 -0.1016)
			(end 0.3048 -0.1016)
			(stroke
				(width 0.1)
				(type default)
			)
			(layer "B.Fab")
		)
		(fp_line
			(start 0.3048 -0.1016)
			(end 0.3048 0.9906)
			(stroke
				(width 0.1)
				(type default)
			)
			(layer "B.Fab")
		)
		(pad "1" smd rect
			(at 0 0 90)
			(size 0.508 0.508)
			(layers "B.Cu" "B.Mask" "B.Paste")
			(net "SATA6G_P5_TX_C_DP")
		)
		(pad "2" smd rect
			(at 0 0.889 90)
			(size 0.508 0.508)
			(layers "B.Cu" "B.Mask" "B.Paste")
			(net "SATA6G_PCH_PCIE_UP_SATA_TXP<5>")
		)
		(zone
			(layer "B.Cu")
			(hatch none 0.5)
			(connect_pads
				(clearance 0)
			)
			(min_thickness 0.25)
			(keepout
				(tracks not_allowed)
				(vias allowed)
				(pads allowed)
				(copperpour not_allowed)
				(footprints allowed)
			)
			(placement
				(enabled no)
				(sheetname "")
			)
			(fill
				(thermal_gap 0.5)
				(thermal_bridge_width 0.5)
				(island_removal_mode 0)
			)
			(polygon
				(pts
					(xy 411.226 -145.161) (xy 411.226 -145.669) (xy 411.607 -145.669) (xy 411.607 -145.161)
				)
			)
		)
		(zone
			(layer "B.Cu")
			(hatch none 0.5)
			(connect_pads
				(clearance 0)
			)
			(min_thickness 0.25)
			(keepout
				(tracks allowed)
				(vias not_allowed)
				(pads allowed)
				(copperpour not_allowed)
				(footprints allowed)
			)
			(placement
				(enabled no)
				(sheetname "")
			)
			(fill
				(thermal_gap 0.5)
				(thermal_bridge_width 0.5)
				(island_removal_mode 0)
			)
			(polygon
				(pts
					(xy 411.607 -145.161) (xy 411.607 -145.669) (xy 411.226 -145.669) (xy 411.226 -145.161)
				)
			)
		)
	)
	(footprint ""
		(layer "B.Cu")
		(at 352.904806 -61.257434)
		(property "Reference" "C2U17"
			(at 0 0 0)
			(layer "B.SilkS")
			(hide yes)
			(effects
				(font
					(size 1.27 1.27)
				)
				(justify mirror)
			)
		)
		(property "Value" ""
			(at 0 0 0)
			(layer "B.Fab")
			(effects
				(font
					(size 1.27 1.27)
				)
				(justify mirror)
			)
		)
		(duplicate_pad_numbers_are_jumpers no)
		(fp_poly
			(pts
				(xy -0.3048 -0.1016) (xy -0.3048 0.9906) (xy 0.3048 0.9906) (xy 0.3048 -0.1016)
			)
			(stroke
				(width 0)
				(type default)
			)
			(fill no)
			(layer "B.CrtYd")
		)
		(fp_line
			(start -0.3048 -0.1016)
			(end 0.3048 -0.1016)
			(stroke
				(width 0.1)
				(type default)
			)
			(layer "B.Fab")
		)
		(fp_line
			(start -0.3048 0.9906)
			(end -0.3048 -0.1016)
			(stroke
				(width 0.1)
				(type default)
			)
			(layer "B.Fab")
		)
		(fp_line
			(start 0.3048 -0.1016)
			(end 0.3048 0.9906)
			(stroke
				(width 0.1)
				(type default)
			)
			(layer "B.Fab")
		)
		(fp_line
			(start 0.3048 0.9906)
			(end -0.3048 0.9906)
			(stroke
				(width 0.1)
				(type default)
			)
			(layer "B.Fab")
		)
		(pad "1" smd rect
			(at 0 0 180)
			(size 0.508 0.508)
			(layers "B.Cu" "B.Mask" "B.Paste")
			(net "P3E_CPU0_PE1_PCH_RXP<7>")
		)
		(pad "2" smd rect
			(at 0 0.889 180)
			(size 0.508 0.508)
			(layers "B.Cu" "B.Mask" "B.Paste")
			(net "P3E_CPU0_PE1_SS_RXP<7>")
		)
		(zone
			(layer "B.Cu")
			(hatch none 0.5)
			(connect_pads
				(clearance 0)
			)
			(min_thickness 0.25)
			(keepout
				(tracks allowed)
				(vias not_allowed)
				(pads allowed)
				(copperpour not_allowed)
				(footprints allowed)
			)
			(placement
				(enabled no)
				(sheetname "")
			)
			(fill
				(thermal_gap 0.5)
				(thermal_bridge_width 0.5)
				(island_removal_mode 0)
			)
			(polygon
				(pts
					(xy 353.158806 -61.003434) (xy 352.650806 -61.003434) (xy 352.650806 -60.622434) (xy 353.158806 -60.622434)
				)
			)
		)
		(zone
			(layer "B.Cu")
			(hatch none 0.5)
			(connect_pads
				(clearance 0)
			)
			(min_thickness 0.25)
			(keepout
				(tracks not_allowed)
				(vias allowed)
				(pads allowed)
				(copperpour not_allowed)
				(footprints allowed)
			)
			(placement
				(enabled no)
				(sheetname "")
			)
			(fill
				(thermal_gap 0.5)
				(thermal_bridge_width 0.5)
				(island_removal_mode 0)
			)
			(polygon
				(pts
					(xy 353.158806 -60.622434) (xy 352.650806 -60.622434) (xy 352.650806 -61.003434) (xy 353.158806 -61.003434)
				)
			)
		)
	)
	(footprint ""
		(layer "B.Cu")
		(at 282.259024 -78.801214 -90)
		(property "Reference" "R4P2"
			(at 0 0 90)
			(layer "B.SilkS")
			(hide yes)
			(effects
				(font
					(size 1.27 1.27)
				)
				(justify mirror)
			)
		)
		(property "Value" ""
			(at 0 0 90)
			(layer "B.Fab")
			(effects
				(font
					(size 1.27 1.27)
				)
				(justify mirror)
			)
		)
		(duplicate_pad_numbers_are_jumpers no)
		(fp_rect
			(start 0.2794 0.9906)
			(end -0.2794 -0.1016)
			(stroke
				(width 0)
				(type default)
			)
			(fill no)
			(layer "B.CrtYd")
		)
		(fp_line
			(start -0.2794 0.9906)
			(end -0.2794 -0.1016)
			(stroke
				(width 0.1)
				(type default)
			)
			(layer "B.Fab")
		)
		(fp_line
			(start 0.2794 0.9906)
			(end -0.2794 0.9906)
			(stroke
				(width 0.1)
				(type default)
			)
			(layer "B.Fab")
		)
		(fp_line
			(start -0.2794 -0.1016)
			(end 0.2794 -0.1016)
			(stroke
				(width 0.1)
				(type default)
			)
			(layer "B.Fab")
		)
		(fp_line
			(start 0.2794 -0.1016)
			(end 0.2794 0.9906)
			(stroke
				(width 0.1)
				(type default)
			)
			(layer "B.Fab")
		)
		(pad "1" smd rect
			(at 0 0 90)
			(size 0.508 0.508)
			(layers "B.Cu" "B.Mask" "B.Paste")
			(net "A_CPU0_PE3_RBIAS")
		)
		(pad "2" smd rect
			(at 0 0.889 90)
			(size 0.508 0.508)
			(layers "B.Cu" "B.Mask" "B.Paste")
			(net "GND")
		)
		(zone
			(layer "B.Cu")
			(hatch none 0.5)
			(connect_pads
				(clearance 0)
			)
			(min_thickness 0.25)
			(keepout
				(tracks not_allowed)
				(vias allowed)
				(pads allowed)
				(copperpour not_allowed)
				(footprints allowed)
			)
			(placement
				(enabled no)
				(sheetname "")
			)
			(fill
				(thermal_gap 0.5)
				(thermal_bridge_width 0.5)
				(island_removal_mode 0)
			)
			(polygon
				(pts
					(xy 281.624024 -78.547214) (xy 282.005024 -78.547214) (xy 282.005024 -79.055214) (xy 281.624024 -79.055214)
				)
			)
		)
		(zone
			(layer "B.Cu")
			(hatch none 0.5)
			(connect_pads
				(clearance 0)
			)
			(min_thickness 0.25)
			(keepout
				(tracks allowed)
				(vias not_allowed)
				(pads allowed)
				(copperpour not_allowed)
				(footprints allowed)
			)
			(placement
				(enabled no)
				(sheetname "")
			)
			(fill
				(thermal_gap 0.5)
				(thermal_bridge_width 0.5)
				(island_removal_mode 0)
			)
			(polygon
				(pts
					(xy 281.624024 -78.547214) (xy 282.005024 -78.547214) (xy 282.005024 -79.055214) (xy 281.624024 -79.055214)
				)
			)
		)
	)
	(footprint ""
		(layer "B.Cu")
		(at -1.06426 -115.3668 -90)
		(property "Reference" "C9M10"
			(at 0 0 90)
			(layer "B.SilkS")
			(hide yes)
			(effects
				(font
					(size 1.27 1.27)
				)
				(justify mirror)
			)
		)
		(property "Value" ""
			(at 0 0 90)
			(layer "B.Fab")
			(effects
				(font
					(size 1.27 1.27)
				)
				(justify mirror)
			)
		)
		(duplicate_pad_numbers_are_jumpers no)
		(fp_poly
			(pts
				(xy 0.7239 -0.2159) (xy -0.7239 -0.2159) (xy -0.7239 1.9939) (xy 0.7239 1.9939)
			)
			(stroke
				(width 0)
				(type default)
			)
			(fill no)
			(layer "B.CrtYd")
		)
		(fp_line
			(start -0.7239 1.9939)
			(end -0.7239 -0.2159)
			(stroke
				(width 0.1)
				(type default)
			)
			(layer "B.Fab")
		)
		(fp_line
			(start 0.7239 1.9939)
			(end -0.7239 1.9939)
			(stroke
				(width 0.1)
				(type default)
			)
			(layer "B.Fab")
		)
		(fp_line
			(start -0.7239 -0.2159)
			(end 0.7239 -0.2159)
			(stroke
				(width 0.1)
				(type default)
			)
			(layer "B.Fab")
		)
		(fp_line
			(start 0.7239 -0.2159)
			(end 0.7239 1.9939)
			(stroke
				(width 0.1)
				(type default)
			)
			(layer "B.Fab")
		)
		(pad "1" smd rect
			(at 0 0 90)
			(size 1.27 1.016)
			(layers "B.Cu" "B.Mask" "B.Paste")
			(net "P12V_STBY")
		)
		(pad "2" smd rect
			(at 0 1.778 90)
			(size 1.27 1.016)
			(layers "B.Cu" "B.Mask" "B.Paste")
			(net "GND")
		)
		(zone
			(layer "B.Cu")
			(hatch none 0.5)
			(connect_pads
				(clearance 0)
			)
			(min_thickness 0.25)
			(keepout
				(tracks not_allowed)
				(vias allowed)
				(pads allowed)
				(copperpour not_allowed)
				(footprints allowed)
			)
			(placement
				(enabled no)
				(sheetname "")
			)
			(fill
				(thermal_gap 0.5)
				(thermal_bridge_width 0.5)
				(island_removal_mode 0)
			)
			(polygon
				(pts
					(xy -1.57226 -114.7318) (xy -1.57226 -116.0018) (xy -2.33426 -116.0018) (xy -2.33426 -114.7318)
				)
			)
		)
	)
	(footprint ""
		(layer "B.Cu")
		(at 406.654 -93.280992 90)
		(property "Reference" "C8C4"
			(at 0 0 90)
			(layer "B.SilkS")
			(hide yes)
			(effects
				(font
					(size 1.27 1.27)
				)
				(justify mirror)
			)
		)
		(property "Value" ""
			(at 0 0 90)
			(layer "B.Fab")
			(effects
				(font
					(size 1.27 1.27)
				)
				(justify mirror)
			)
		)
		(duplicate_pad_numbers_are_jumpers no)
		(fp_poly
			(pts
				(xy 0.4953 -0.2032) (xy -0.4953 -0.2032) (xy -0.4953 1.6002) (xy 0.4953 1.6002)
			)
			(stroke
				(width 0)
				(type default)
			)
			(fill no)
			(layer "B.CrtYd")
		)
		(fp_line
			(start 0.4953 -0.2032)
			(end -0.4953 -0.2032)
			(stroke
				(width 0.1)
				(type default)
			)
			(layer "B.Fab")
		)
		(fp_line
			(start -0.4953 -0.2032)
			(end -0.4953 1.6002)
			(stroke
				(width 0.1)
				(type default)
			)
			(layer "B.Fab")
		)
		(fp_line
			(start 0.4953 1.6002)
			(end 0.4953 -0.2032)
			(stroke
				(width 0.1)
				(type default)
			)
			(layer "B.Fab")
		)
		(fp_line
			(start -0.4953 1.6002)
			(end 0.4953 1.6002)
			(stroke
				(width 0.1)
				(type default)
			)
			(layer "B.Fab")
		)
		(pad "1" smd rect
			(at 0 0 270)
			(size 0.762 0.889)
			(layers "B.Cu" "B.Mask" "B.Paste")
			(net "P3V3_STBY")
		)
		(pad "2" smd rect
			(at 0 1.397 270)
			(size 0.762 0.889)
			(layers "B.Cu" "B.Mask" "B.Paste")
			(net "GND")
		)
		(zone
			(layer "B.Cu")
			(hatch none 0.5)
			(connect_pads
				(clearance 0)
			)
			(min_thickness 0.25)
			(keepout
				(tracks not_allowed)
				(vias allowed)
				(pads allowed)
				(copperpour not_allowed)
				(footprints allowed)
			)
			(placement
				(enabled no)
				(sheetname "")
			)
			(fill
				(thermal_gap 0.5)
				(thermal_bridge_width 0.5)
				(island_removal_mode 0)
			)
			(polygon
				(pts
					(xy 407.0985 -93.661992) (xy 407.0985 -92.899992) (xy 407.6065 -92.899992) (xy 407.6065 -93.661992)
				)
			)
		)
	)
	(footprint ""
		(layer "B.Cu")
		(at 495.45748 -130.52552)
		(property "Reference" "C1M32"
			(at 0 0 0)
			(layer "B.SilkS")
			(hide yes)
			(effects
				(font
					(size 1.27 1.27)
				)
				(justify mirror)
			)
		)
		(property "Value" ""
			(at 0 0 0)
			(layer "B.Fab")
			(effects
				(font
					(size 1.27 1.27)
				)
				(justify mirror)
			)
		)
		(duplicate_pad_numbers_are_jumpers no)
		(fp_poly
			(pts
				(xy -0.3048 -0.1016) (xy -0.3048 0.9906) (xy 0.3048 0.9906) (xy 0.3048 -0.1016)
			)
			(stroke
				(width 0)
				(type default)
			)
			(fill no)
			(layer "B.CrtYd")
		)
		(fp_line
			(start -0.3048 -0.1016)
			(end 0.3048 -0.1016)
			(stroke
				(width 0.1)
				(type default)
			)
			(layer "B.Fab")
		)
		(fp_line
			(start -0.3048 0.9906)
			(end -0.3048 -0.1016)
			(stroke
				(width 0.1)
				(type default)
			)
			(layer "B.Fab")
		)
		(fp_line
			(start 0.3048 -0.1016)
			(end 0.3048 0.9906)
			(stroke
				(width 0.1)
				(type default)
			)
			(layer "B.Fab")
		)
		(fp_line
			(start 0.3048 0.9906)
			(end -0.3048 0.9906)
			(stroke
				(width 0.1)
				(type default)
			)
			(layer "B.Fab")
		)
		(pad "1" smd rect
			(at 0 0 180)
			(size 0.508 0.508)
			(layers "B.Cu" "B.Mask" "B.Paste")
			(net "P3V3_STBY")
		)
		(pad "2" smd rect
			(at 0 0.889 180)
			(size 0.508 0.508)
			(layers "B.Cu" "B.Mask" "B.Paste")
			(net "GND")
		)
		(zone
			(layer "B.Cu")
			(hatch none 0.5)
			(connect_pads
				(clearance 0)
			)
			(min_thickness 0.25)
			(keepout
				(tracks allowed)
				(vias not_allowed)
				(pads allowed)
				(copperpour not_allowed)
				(footprints allowed)
			)
			(placement
				(enabled no)
				(sheetname "")
			)
			(fill
				(thermal_gap 0.5)
				(thermal_bridge_width 0.5)
				(island_removal_mode 0)
			)
			(polygon
				(pts
					(xy 495.71148 -130.27152) (xy 495.20348 -130.27152) (xy 495.20348 -129.89052) (xy 495.71148 -129.89052)
				)
			)
		)
		(zone
			(layer "B.Cu")
			(hatch none 0.5)
			(connect_pads
				(clearance 0)
			)
			(min_thickness 0.25)
			(keepout
				(tracks not_allowed)
				(vias allowed)
				(pads allowed)
				(copperpour not_allowed)
				(footprints allowed)
			)
			(placement
				(enabled no)
				(sheetname "")
			)
			(fill
				(thermal_gap 0.5)
				(thermal_bridge_width 0.5)
				(island_removal_mode 0)
			)
			(polygon
				(pts
					(xy 495.71148 -129.89052) (xy 495.20348 -129.89052) (xy 495.20348 -130.27152) (xy 495.71148 -130.27152)
				)
			)
		)
	)
	(footprint ""
		(layer "B.Cu")
		(at 327.914 -61.849 -90)
		(property "Reference" "R4R2"
			(at 0 0 90)
			(layer "B.SilkS")
			(hide yes)
			(effects
				(font
					(size 1.27 1.27)
				)
				(justify mirror)
			)
		)
		(property "Value" ""
			(at 0 0 90)
			(layer "B.Fab")
			(effects
				(font
					(size 1.27 1.27)
				)
				(justify mirror)
			)
		)
		(duplicate_pad_numbers_are_jumpers no)
		(fp_poly
			(pts
				(xy 0.2794 -0.1016) (xy -0.2794 -0.1016) (xy -0.2794 0.9906) (xy 0.2794 0.9906)
			)
			(stroke
				(width 0)
				(type default)
			)
			(fill no)
			(layer "B.CrtYd")
		)
		(fp_line
			(start -0.2794 0.9906)
			(end -0.2794 -0.1016)
			(stroke
				(width 0.1)
				(type default)
			)
			(layer "B.Fab")
		)
		(fp_line
			(start 0.2794 0.9906)
			(end -0.2794 0.9906)
			(stroke
				(width 0.1)
				(type default)
			)
			(layer "B.Fab")
		)
		(fp_line
			(start -0.2794 -0.1016)
			(end 0.2794 -0.1016)
			(stroke
				(width 0.1)
				(type default)
			)
			(layer "B.Fab")
		)
		(fp_line
			(start 0.2794 -0.1016)
			(end 0.2794 0.9906)
			(stroke
				(width 0.1)
				(type default)
			)
			(layer "B.Fab")
		)
		(pad "1" smd rect
			(at 0 0 90)
			(size 0.508 0.508)
			(layers "B.Cu" "B.Mask" "B.Paste")
			(net "PVCCIO_CPU0")
		)
		(pad "2" smd rect
			(at 0 0.889 90)
			(size 0.508 0.508)
			(layers "B.Cu" "B.Mask" "B.Paste")
			(net "H_CPU0_CATERR_G_N")
		)
		(zone
			(layer "B.Cu")
			(hatch none 0.5)
			(connect_pads
				(clearance 0)
			)
			(min_thickness 0.25)
			(keepout
				(tracks not_allowed)
				(vias allowed)
				(pads allowed)
				(copperpour not_allowed)
				(footprints allowed)
			)
			(placement
				(enabled no)
				(sheetname "")
			)
			(fill
				(thermal_gap 0.5)
				(thermal_bridge_width 0.5)
				(island_removal_mode 0)
			)
			(polygon
				(pts
					(xy 327.279 -61.595) (xy 327.279 -62.103) (xy 327.66 -62.103) (xy 327.66 -61.595)
				)
			)
		)
		(zone
			(layer "B.Cu")
			(hatch none 0.5)
			(connect_pads
				(clearance 0)
			)
			(min_thickness 0.25)
			(keepout
				(tracks allowed)
				(vias not_allowed)
				(pads allowed)
				(copperpour not_allowed)
				(footprints allowed)
			)
			(placement
				(enabled no)
				(sheetname "")
			)
			(fill
				(thermal_gap 0.5)
				(thermal_bridge_width 0.5)
				(island_removal_mode 0)
			)
			(polygon
				(pts
					(xy 327.66 -61.595) (xy 327.66 -62.103) (xy 327.279 -62.103) (xy 327.279 -61.595)
				)
			)
		)
	)
	(footprint ""
		(layer "B.Cu")
		(at 259.999734 4.003548 90)
		(property "Reference" "C5U16"
			(at -1.47828 0.78994 180)
			(unlocked yes)
			(layer "B.SilkS")
			(effects
				(font
					(size 0.4064 0.254)
					(thickness 0.1524)
				)
				(justify mirror)
			)
		)
		(property "Value" ""
			(at 0 0 90)
			(layer "B.Fab")
			(effects
				(font
					(size 1.27 1.27)
				)
				(justify mirror)
			)
		)
		(duplicate_pad_numbers_are_jumpers no)
		(fp_poly
			(pts
				(xy 0.7239 -0.2159) (xy -0.7239 -0.2159) (xy -0.7239 1.9939) (xy 0.7239 1.9939)
			)
			(stroke
				(width 0)
				(type default)
			)
			(fill no)
			(layer "B.CrtYd")
		)
		(fp_line
			(start 0.7239 -0.2159)
			(end 0.7239 1.9939)
			(stroke
				(width 0.1)
				(type default)
			)
			(layer "B.Fab")
		)
		(fp_line
			(start -0.7239 -0.2159)
			(end 0.7239 -0.2159)
			(stroke
				(width 0.1)
				(type default)
			)
			(layer "B.Fab")
		)
		(fp_line
			(start 0.7239 1.9939)
			(end -0.7239 1.9939)
			(stroke
				(width 0.1)
				(type default)
			)
			(layer "B.Fab")
		)
		(fp_line
			(start -0.7239 1.9939)
			(end -0.7239 -0.2159)
			(stroke
				(width 0.1)
				(type default)
			)
			(layer "B.Fab")
		)
		(pad "1" smd rect
			(at 0 0 270)
			(size 1.27 1.016)
			(layers "B.Cu" "B.Mask" "B.Paste")
			(net "PVTT_ABC")
		)
		(pad "2" smd rect
			(at 0 1.778 270)
			(size 1.27 1.016)
			(layers "B.Cu" "B.Mask" "B.Paste")
			(net "GND")
		)
		(zone
			(layer "B.Cu")
			(hatch none 0.5)
			(connect_pads
				(clearance 0)
			)
			(min_thickness 0.25)
			(keepout
				(tracks not_allowed)
				(vias allowed)
				(pads allowed)
				(copperpour not_allowed)
				(footprints allowed)
			)
			(placement
				(enabled no)
				(sheetname "")
			)
			(fill
				(thermal_gap 0.5)
				(thermal_bridge_width 0.5)
				(island_removal_mode 0)
			)
			(polygon
				(pts
					(xy 260.507734 3.368548) (xy 260.507734 4.638548) (xy 261.269734 4.638548) (xy 261.269734 3.368548)
				)
			)
		)
	)
)
